(kicad_pcb
	(version 20260206)
	(generator "pcbnew")
	(generator_version "10.0")
	(general
		(thickness 1.6)
		(legacy_teardrops no)
	)
	(paper "A4")
	(title_block
		(title "01162023_DA0F0TEBIF0_F0T_Expander_BD_F_brd_V02_OCP.brd")
		(comment 1 "Grand Teton / footprints 5655-5659 of 9728")
	)
	(layers
		(0 "F.Cu" signal "TOP")
		(4 "In1.Cu" signal "GND")
		(6 "In2.Cu" signal "VCC")
		(8 "In3.Cu" signal "VCC1")
		(10 "In4.Cu" signal "GND1")
		(12 "In5.Cu" signal "IN1")
		(14 "In6.Cu" signal "GND2")
		(16 "In7.Cu" signal "IN2")
		(18 "In8.Cu" signal "GND3")
		(20 "In9.Cu" signal "IN3")
		(22 "In10.Cu" signal "GND4")
		(24 "In11.Cu" signal "IN4")
		(26 "In12.Cu" signal "GND5")
		(28 "In13.Cu" signal "IN5")
		(30 "In14.Cu" signal "GND6")
		(32 "In15.Cu" signal "IN6")
		(34 "In16.Cu" signal "GND7")
		(2 "B.Cu" signal "BOTTOM")
		(9 "F.Adhes" user "F.Adhesive")
		(11 "B.Adhes" user "B.Adhesive")
		(13 "F.Paste" user "Package Geometry/Pastemask Top")
		(15 "B.Paste" user "Package Geometry/Pastemask Bottom")
		(5 "F.SilkS" user "Ref Des/Silkscreen Top")
		(7 "B.SilkS" user "Ref Des/Silkscreen Bottom")
		(1 "F.Mask" user "Board Geometry/Soldermask Top")
		(3 "B.Mask" user "Board Geometry/Soldermask Bottom")
		(17 "Dwgs.User" user "User.Drawings")
		(19 "Cmts.User" user "User.Comments")
		(21 "Eco1.User" user "User.Eco1")
		(23 "Eco2.User" user "User.Eco2")
		(25 "Edge.Cuts" user "Board Geometry/Outline")
		(27 "Margin" user)
		(31 "F.CrtYd" user "Package Geometry/Place Bound Top")
		(29 "B.CrtYd" user "Package Geometry/Place Bound Bottom")
		(35 "F.Fab" user "Ref Des/Assembly Top")
		(33 "B.Fab" user "Ref Des/Assembly Bottom")
	)
	(footprint ""
		(layer "F.Cu")
		(at 240.862612 -242.808506 -90)
		(property "Reference" "U419"
			(at 1.406906 -4.807458 90)
			(unlocked yes)
			(layer "F.SilkS")
			(effects
				(font
					(size 0.7874 0.5842)
					(thickness 0.1524)
				)
				(justify left)
			)
		)
		(property "Value" ""
			(at 0 0 270)
			(layer "F.Fab")
			(effects
				(font
					(size 1.27 1.27)
				)
			)
		)
		(duplicate_pad_numbers_are_jumpers no)
		(fp_line
			(start -2.097532 3.949954)
			(end 2.097532 3.949954)
			(stroke
				(width 0.1524)
				(type default)
			)
			(layer "F.SilkS")
		)
		(fp_line
			(start 2.097532 3.949954)
			(end 2.097532 -3.949954)
			(stroke
				(width 0.1524)
				(type default)
			)
			(layer "F.SilkS")
		)
		(fp_line
			(start 0 -2.54)
			(end -1.409954 -3.949954)
			(stroke
				(width 0.1524)
				(type default)
			)
			(layer "F.SilkS")
		)
		(fp_line
			(start -2.097532 -3.949954)
			(end -2.097532 3.949954)
			(stroke
				(width 0.1524)
				(type default)
			)
			(layer "F.SilkS")
		)
		(fp_line
			(start -1.409954 -3.949954)
			(end -2.097532 -3.949954)
			(stroke
				(width 0.1524)
				(type default)
			)
			(layer "F.SilkS")
		)
		(fp_line
			(start 1.409954 -3.949954)
			(end 0 -2.54)
			(stroke
				(width 0.1524)
				(type default)
			)
			(layer "F.SilkS")
		)
		(fp_line
			(start 2.097532 -3.949954)
			(end 1.409954 -3.949954)
			(stroke
				(width 0.1524)
				(type default)
			)
			(layer "F.SilkS")
		)
		(fp_poly
			(pts
				(xy -4.7498 -4.182872) (xy -4.7498 -3.166872) (xy -3.7338 -3.674872)
			)
			(stroke
				(width 0)
				(type default)
			)
			(fill yes)
			(layer "F.SilkS")
		)
		(fp_line
			(start -2.249932 3.949954)
			(end 2.249932 3.949954)
			(stroke
				(width 0.1)
				(type default)
			)
			(layer "F.Fab")
		)
		(fp_line
			(start 2.249932 3.949954)
			(end 2.249932 -3.949954)
			(stroke
				(width 0.1)
				(type default)
			)
			(layer "F.Fab")
		)
		(fp_line
			(start -2.249932 -3.949954)
			(end -2.249932 3.949954)
			(stroke
				(width 0.1)
				(type default)
			)
			(layer "F.Fab")
		)
		(fp_line
			(start 2.249932 -3.949954)
			(end -2.249932 -3.949954)
			(stroke
				(width 0.1)
				(type default)
			)
			(layer "F.Fab")
		)
		(fp_poly
			(pts
				(xy -4.7498 -4.182872) (xy -4.7498 -3.166872) (xy -3.7338 -3.674872)
			)
			(stroke
				(width 0)
				(type default)
			)
			(fill yes)
			(layer "F.Fab")
		)
		(pad "1" smd rect
			(at -2.925064 -3.674872 180)
			(size 0.6096 1.3716)
			(layers "F.Cu" "F.Mask" "F.Paste")
			(net "IRQ_BIC_RECOVER_IOEXP_N")
		)
		(pad "2" smd rect
			(at -2.925064 -2.925064 180)
			(size 0.4064 1.3716)
			(layers "F.Cu" "F.Mask" "F.Paste")
			(net "BIC_RECOVER_IOEXP_A1")
		)
		(pad "3" smd rect
			(at -2.925064 -2.275078 180)
			(size 0.4064 1.3716)
			(layers "F.Cu" "F.Mask" "F.Paste")
			(net "RST_BIC_RECOVER_N")
		)
		(pad "4" smd rect
			(at -2.925064 -1.625092 180)
			(size 0.4064 1.3716)
			(layers "F.Cu" "F.Mask" "F.Paste")
			(net "BIC_FWSPICK_IOEXP")
		)
		(pad "5" smd rect
			(at -2.925064 -0.975106 180)
			(size 0.4064 1.3716)
			(layers "F.Cu" "F.Mask" "F.Paste")
			(net "BIC_UART_BMC_SEL")
		)
		(pad "6" smd rect
			(at -2.925064 -0.32512 180)
			(size 0.4064 1.3716)
			(layers "F.Cu" "F.Mask" "F.Paste")
			(net "Net_9120")
		)
		(pad "7" smd rect
			(at -2.925064 0.32512 180)
			(size 0.4064 1.3716)
			(layers "F.Cu" "F.Mask" "F.Paste")
			(net "Net_9119")
		)
		(pad "8" smd rect
			(at -2.925064 0.975106 180)
			(size 0.4064 1.3716)
			(layers "F.Cu" "F.Mask" "F.Paste")
			(net "Net_9118")
		)
		(pad "9" smd rect
			(at -2.925064 1.625092 180)
			(size 0.4064 1.3716)
			(layers "F.Cu" "F.Mask" "F.Paste")
			(net "Net_9117")
		)
		(pad "10" smd rect
			(at -2.925064 2.275078 180)
			(size 0.4064 1.3716)
			(layers "F.Cu" "F.Mask" "F.Paste")
			(net "Net_9116")
		)
		(pad "11" smd rect
			(at -2.925064 2.925064 180)
			(size 0.4064 1.3716)
			(layers "F.Cu" "F.Mask" "F.Paste")
			(net "Net_9115")
		)
		(pad "12" smd rect
			(at -2.925064 3.674872 180)
			(size 0.6096 1.3716)
			(layers "F.Cu" "F.Mask" "F.Paste")
			(net "GND")
		)
		(pad "13" smd rect
			(at 2.925064 3.674872 180)
			(size 0.6096 1.3716)
			(layers "F.Cu" "F.Mask" "F.Paste")
			(net "Net_9114")
		)
		(pad "14" smd rect
			(at 2.925064 2.925064 180)
			(size 0.4064 1.3716)
			(layers "F.Cu" "F.Mask" "F.Paste")
			(net "Net_9113")
		)
		(pad "15" smd rect
			(at 2.925064 2.275078 180)
			(size 0.4064 1.3716)
			(layers "F.Cu" "F.Mask" "F.Paste")
			(net "Net_9112")
		)
		(pad "16" smd rect
			(at 2.925064 1.625092 180)
			(size 0.4064 1.3716)
			(layers "F.Cu" "F.Mask" "F.Paste")
			(net "Net_9111")
		)
		(pad "17" smd rect
			(at 2.925064 0.975106 180)
			(size 0.4064 1.3716)
			(layers "F.Cu" "F.Mask" "F.Paste")
			(net "Net_9110")
		)
		(pad "18" smd rect
			(at 2.925064 0.32512 180)
			(size 0.4064 1.3716)
			(layers "F.Cu" "F.Mask" "F.Paste")
			(net "Net_9109")
		)
		(pad "19" smd rect
			(at 2.925064 -0.32512 180)
			(size 0.4064 1.3716)
			(layers "F.Cu" "F.Mask" "F.Paste")
			(net "Net_9108")
		)
		(pad "20" smd rect
			(at 2.925064 -0.975106 180)
			(size 0.4064 1.3716)
			(layers "F.Cu" "F.Mask" "F.Paste")
			(net "Net_9107")
		)
		(pad "21" smd rect
			(at 2.925064 -1.625092 180)
			(size 0.4064 1.3716)
			(layers "F.Cu" "F.Mask" "F.Paste")
			(net "BIC_RECOVER_IOEXP_A0")
		)
		(pad "22" smd rect
			(at 2.925064 -2.275078 180)
			(size 0.4064 1.3716)
			(layers "F.Cu" "F.Mask" "F.Paste")
			(net "SMB_BIC_RECOVER_IOEXP_SCL")
		)
		(pad "23" smd rect
			(at 2.925064 -2.925064 180)
			(size 0.4064 1.3716)
			(layers "F.Cu" "F.Mask" "F.Paste")
			(net "SMB_BIC_RECOVER_IOEXP_SDA")
		)
		(pad "24" smd rect
			(at 2.925064 -3.674872 180)
			(size 0.6096 1.3716)
			(layers "F.Cu" "F.Mask" "F.Paste")
			(net "P3V3_AUX")
		)
	)
	(footprint ""
		(layer "F.Cu")
		(at 213.801198 -219.306902)
		(property "Reference" "R4873"
			(at 0 0 0)
			(layer "F.SilkS")
			(hide yes)
			(effects
				(font
					(size 1.27 1.27)
				)
			)
		)
		(property "Value" ""
			(at 0 0 0)
			(layer "F.Fab")
			(effects
				(font
					(size 1.27 1.27)
				)
			)
		)
		(duplicate_pad_numbers_are_jumpers no)
		(fp_line
			(start -0.7874 -0.4064)
			(end 0.7874 -0.4064)
			(stroke
				(width 0.1524)
				(type default)
			)
			(layer "F.SilkS")
		)
		(fp_line
			(start -0.7874 0.4064)
			(end -0.7874 -0.4064)
			(stroke
				(width 0.1524)
				(type default)
			)
			(layer "F.SilkS")
		)
		(fp_line
			(start 0.7874 -0.4064)
			(end 0.7874 0.4064)
			(stroke
				(width 0.1524)
				(type default)
			)
			(layer "F.SilkS")
		)
		(fp_line
			(start 0.7874 0.4064)
			(end -0.7874 0.4064)
			(stroke
				(width 0.1524)
				(type default)
			)
			(layer "F.SilkS")
		)
		(fp_line
			(start -0.67945 -0.305054)
			(end -0.12065 -0.305054)
			(stroke
				(width 0.1)
				(type default)
			)
			(layer "F.Fab")
		)
		(fp_line
			(start -0.67945 0.3048)
			(end -0.67945 -0.305054)
			(stroke
				(width 0.1)
				(type default)
			)
			(layer "F.Fab")
		)
		(fp_line
			(start -0.12065 -0.305054)
			(end -0.12065 -0.2794)
			(stroke
				(width 0.1)
				(type default)
			)
			(layer "F.Fab")
		)
		(fp_line
			(start -0.12065 -0.2794)
			(end 0.12065 -0.2794)
			(stroke
				(width 0.1)
				(type default)
			)
			(layer "F.Fab")
		)
		(fp_line
			(start -0.12065 0.2794)
			(end -0.12065 0.3048)
			(stroke
				(width 0.1)
				(type default)
			)
			(layer "F.Fab")
		)
		(fp_line
			(start -0.12065 0.3048)
			(end -0.67945 0.3048)
			(stroke
				(width 0.1)
				(type default)
			)
			(layer "F.Fab")
		)
		(fp_line
			(start 0.120396 0.2794)
			(end -0.12065 0.2794)
			(stroke
				(width 0.1)
				(type default)
			)
			(layer "F.Fab")
		)
		(fp_line
			(start 0.120396 0.3048)
			(end 0.120396 0.2794)
			(stroke
				(width 0.1)
				(type default)
			)
			(layer "F.Fab")
		)
		(fp_line
			(start 0.12065 -0.3048)
			(end 0.67945 -0.3048)
			(stroke
				(width 0.1)
				(type default)
			)
			(layer "F.Fab")
		)
		(fp_line
			(start 0.12065 -0.2794)
			(end 0.12065 -0.3048)
			(stroke
				(width 0.1)
				(type default)
			)
			(layer "F.Fab")
		)
		(fp_line
			(start 0.67945 -0.3048)
			(end 0.67945 0.3048)
			(stroke
				(width 0.1)
				(type default)
			)
			(layer "F.Fab")
		)
		(fp_line
			(start 0.67945 0.3048)
			(end 0.120396 0.3048)
			(stroke
				(width 0.1)
				(type default)
			)
			(layer "F.Fab")
		)
		(pad "1" smd circle
			(at -0.40005 0)
			(size 0 0)
			(layers "F.Cu" "F.Mask" "F.Paste")
			(net "P1V2_AUX")
		)
		(pad "2" smd circle
			(at 0.40005 0)
			(size 0 0)
			(layers "F.Cu" "F.Mask" "F.Paste")
			(net "SMB_NIC4_SCL")
		)
	)
	(footprint ""
		(layer "F.Cu")
		(at 106.298492 -5.747258)
		(property "Reference" "R1648"
			(at 0 0 0)
			(layer "F.SilkS")
			(hide yes)
			(effects
				(font
					(size 1.27 1.27)
				)
			)
		)
		(property "Value" ""
			(at 0 0 0)
			(layer "F.Fab")
			(effects
				(font
					(size 1.27 1.27)
				)
			)
		)
		(duplicate_pad_numbers_are_jumpers no)
		(fp_line
			(start -0.7874 -0.4064)
			(end 0.7874 -0.4064)
			(stroke
				(width 0.1524)
				(type default)
			)
			(layer "F.SilkS")
		)
		(fp_line
			(start -0.7874 0.4064)
			(end -0.7874 -0.4064)
			(stroke
				(width 0.1524)
				(type default)
			)
			(layer "F.SilkS")
		)
		(fp_line
			(start 0.7874 -0.4064)
			(end 0.7874 0.4064)
			(stroke
				(width 0.1524)
				(type default)
			)
			(layer "F.SilkS")
		)
		(fp_line
			(start 0.7874 0.4064)
			(end -0.7874 0.4064)
			(stroke
				(width 0.1524)
				(type default)
			)
			(layer "F.SilkS")
		)
		(fp_line
			(start -0.67945 -0.305054)
			(end -0.12065 -0.305054)
			(stroke
				(width 0.1)
				(type default)
			)
			(layer "F.Fab")
		)
		(fp_line
			(start -0.67945 0.3048)
			(end -0.67945 -0.305054)
			(stroke
				(width 0.1)
				(type default)
			)
			(layer "F.Fab")
		)
		(fp_line
			(start -0.12065 -0.305054)
			(end -0.12065 -0.2794)
			(stroke
				(width 0.1)
				(type default)
			)
			(layer "F.Fab")
		)
		(fp_line
			(start -0.12065 -0.2794)
			(end 0.12065 -0.2794)
			(stroke
				(width 0.1)
				(type default)
			)
			(layer "F.Fab")
		)
		(fp_line
			(start -0.12065 0.2794)
			(end -0.12065 0.3048)
			(stroke
				(width 0.1)
				(type default)
			)
			(layer "F.Fab")
		)
		(fp_line
			(start -0.12065 0.3048)
			(end -0.67945 0.3048)
			(stroke
				(width 0.1)
				(type default)
			)
			(layer "F.Fab")
		)
		(fp_line
			(start 0.120396 0.2794)
			(end -0.12065 0.2794)
			(stroke
				(width 0.1)
				(type default)
			)
			(layer "F.Fab")
		)
		(fp_line
			(start 0.120396 0.3048)
			(end 0.120396 0.2794)
			(stroke
				(width 0.1)
				(type default)
			)
			(layer "F.Fab")
		)
		(fp_line
			(start 0.12065 -0.3048)
			(end 0.67945 -0.3048)
			(stroke
				(width 0.1)
				(type default)
			)
			(layer "F.Fab")
		)
		(fp_line
			(start 0.12065 -0.2794)
			(end 0.12065 -0.3048)
			(stroke
				(width 0.1)
				(type default)
			)
			(layer "F.Fab")
		)
		(fp_line
			(start 0.67945 -0.3048)
			(end 0.67945 0.3048)
			(stroke
				(width 0.1)
				(type default)
			)
			(layer "F.Fab")
		)
		(fp_line
			(start 0.67945 0.3048)
			(end 0.120396 0.3048)
			(stroke
				(width 0.1)
				(type default)
			)
			(layer "F.Fab")
		)
		(pad "1" smd circle
			(at -0.40005 0)
			(size 0 0)
			(layers "F.Cu" "F.Mask" "F.Paste")
			(net "SMB_SSD3_ISO_EN")
		)
		(pad "2" smd circle
			(at 0.40005 0)
			(size 0 0)
			(layers "F.Cu" "F.Mask" "F.Paste")
			(net "P3V3_AUX")
		)
	)
	(footprint ""
		(layer "F.Cu")
		(at 52.267866 -51.019456)
		(property "Reference" "PC374"
			(at 0 0 0)
			(layer "F.SilkS")
			(hide yes)
			(effects
				(font
					(size 1.27 1.27)
				)
			)
		)
		(property "Value" ""
			(at 0 0 0)
			(layer "F.Fab")
			(effects
				(font
					(size 1.27 1.27)
				)
			)
		)
		(duplicate_pad_numbers_are_jumpers no)
		(fp_line
			(start -0.7874 -0.4064)
			(end 0.7874 -0.4064)
			(stroke
				(width 0.1524)
				(type default)
			)
			(layer "F.SilkS")
		)
		(fp_line
			(start -0.7874 0.4064)
			(end -0.7874 -0.4064)
			(stroke
				(width 0.1524)
				(type default)
			)
			(layer "F.SilkS")
		)
		(fp_line
			(start 0.7874 -0.4064)
			(end 0.7874 0.4064)
			(stroke
				(width 0.1524)
				(type default)
			)
			(layer "F.SilkS")
		)
		(fp_line
			(start 0.7874 0.4064)
			(end -0.7874 0.4064)
			(stroke
				(width 0.1524)
				(type default)
			)
			(layer "F.SilkS")
		)
		(fp_line
			(start -0.6858 -0.3048)
			(end -0.1016 -0.3048)
			(stroke
				(width 0.1)
				(type default)
			)
			(layer "F.Fab")
		)
		(fp_line
			(start -0.6858 0.3048)
			(end -0.6858 -0.3048)
			(stroke
				(width 0.1)
				(type default)
			)
			(layer "F.Fab")
		)
		(fp_line
			(start -0.1016 -0.3048)
			(end -0.1016 -0.2794)
			(stroke
				(width 0.1)
				(type default)
			)
			(layer "F.Fab")
		)
		(fp_line
			(start -0.1016 -0.2794)
			(end 0.1016 -0.2794)
			(stroke
				(width 0.1)
				(type default)
			)
			(layer "F.Fab")
		)
		(fp_line
			(start -0.1016 0.2794)
			(end -0.1016 0.3048)
			(stroke
				(width 0.1)
				(type default)
			)
			(layer "F.Fab")
		)
		(fp_line
			(start -0.1016 0.3048)
			(end -0.6858 0.3048)
			(stroke
				(width 0.1)
				(type default)
			)
			(layer "F.Fab")
		)
		(fp_line
			(start 0.1016 -0.3048)
			(end 0.6858 -0.3048)
			(stroke
				(width 0.1)
				(type default)
			)
			(layer "F.Fab")
		)
		(fp_line
			(start 0.1016 -0.2794)
			(end 0.1016 -0.3048)
			(stroke
				(width 0.1)
				(type default)
			)
			(layer "F.Fab")
		)
		(fp_line
			(start 0.1016 0.2794)
			(end -0.1016 0.2794)
			(stroke
				(width 0.1)
				(type default)
			)
			(layer "F.Fab")
		)
		(fp_line
			(start 0.1016 0.3048)
			(end 0.1016 0.2794)
			(stroke
				(width 0.1)
				(type default)
			)
			(layer "F.Fab")
		)
		(fp_line
			(start 0.6858 -0.3048)
			(end 0.6858 0.3048)
			(stroke
				(width 0.1)
				(type default)
			)
			(layer "F.Fab")
		)
		(fp_line
			(start 0.6858 0.3048)
			(end 0.1016 0.3048)
			(stroke
				(width 0.1)
				(type default)
			)
			(layer "F.Fab")
		)
		(pad "1" smd rect
			(at -0.40005 0 180)
			(size 0.4572 0.508)
			(layers "F.Cu" "F.Mask" "F.Paste")
			(net "P12V_SSD1_SS")
		)
		(pad "2" smd rect
			(at 0.40005 0 180)
			(size 0.4572 0.508)
			(layers "F.Cu" "F.Mask" "F.Paste")
			(net "GND")
		)
	)
	(footprint ""
		(layer "F.Cu")
		(at 223.586294 -177.53838 180)
		(property "Reference" "R3144"
			(at 0 0 180)
			(layer "F.SilkS")
			(hide yes)
			(effects
				(font
					(size 1.27 1.27)
				)
			)
		)
		(property "Value" ""
			(at 0 0 180)
			(layer "F.Fab")
			(effects
				(font
					(size 1.27 1.27)
				)
			)
		)
		(duplicate_pad_numbers_are_jumpers no)
		(fp_line
			(start 0.7874 0.4064)
			(end -0.7874 0.4064)
			(stroke
				(width 0.1524)
				(type default)
			)
			(layer "F.SilkS")
		)
		(fp_line
			(start 0.7874 -0.4064)
			(end 0.7874 0.4064)
			(stroke
				(width 0.1524)
				(type default)
			)
			(layer "F.SilkS")
		)
		(fp_line
			(start -0.7874 0.4064)
			(end -0.7874 -0.4064)
			(stroke
				(width 0.1524)
				(type default)
			)
			(layer "F.SilkS")
		)
		(fp_line
			(start -0.7874 -0.4064)
			(end 0.7874 -0.4064)
			(stroke
				(width 0.1524)
				(type default)
			)
			(layer "F.SilkS")
		)
		(fp_line
			(start 0.67945 0.3048)
			(end 0.120396 0.3048)
			(stroke
				(width 0.1)
				(type default)
			)
			(layer "F.Fab")
		)
		(fp_line
			(start 0.67945 -0.3048)
			(end 0.67945 0.3048)
			(stroke
				(width 0.1)
				(type default)
			)
			(layer "F.Fab")
		)
		(fp_line
			(start 0.12065 -0.2794)
			(end 0.12065 -0.3048)
			(stroke
				(width 0.1)
				(type default)
			)
			(layer "F.Fab")
		)
		(fp_line
			(start 0.12065 -0.3048)
			(end 0.67945 -0.3048)
			(stroke
				(width 0.1)
				(type default)
			)
			(layer "F.Fab")
		)
		(fp_line
			(start 0.120396 0.3048)
			(end 0.120396 0.2794)
			(stroke
				(width 0.1)
				(type default)
			)
			(layer "F.Fab")
		)
		(fp_line
			(start 0.120396 0.2794)
			(end -0.12065 0.2794)
			(stroke
				(width 0.1)
				(type default)
			)
			(layer "F.Fab")
		)
		(fp_line
			(start -0.12065 0.3048)
			(end -0.67945 0.3048)
			(stroke
				(width 0.1)
				(type default)
			)
			(layer "F.Fab")
		)
		(fp_line
			(start -0.12065 0.2794)
			(end -0.12065 0.3048)
			(stroke
				(width 0.1)
				(type default)
			)
			(layer "F.Fab")
		)
		(fp_line
			(start -0.12065 -0.2794)
			(end 0.12065 -0.2794)
			(stroke
				(width 0.1)
				(type default)
			)
			(layer "F.Fab")
		)
		(fp_line
			(start -0.12065 -0.305054)
			(end -0.12065 -0.2794)
			(stroke
				(width 0.1)
				(type default)
			)
			(layer "F.Fab")
		)
		(fp_line
			(start -0.67945 0.3048)
			(end -0.67945 -0.305054)
			(stroke
				(width 0.1)
				(type default)
			)
			(layer "F.Fab")
		)
		(fp_line
			(start -0.67945 -0.305054)
			(end -0.12065 -0.305054)
			(stroke
				(width 0.1)
				(type default)
			)
			(layer "F.Fab")
		)
		(pad "1" smd circle
			(at -0.40005 0 180)
			(size 0 0)
			(layers "F.Cu" "F.Mask" "F.Paste")
			(net "ADM1085_CEXT")
		)
		(pad "2" smd circle
			(at 0.40005 0 180)
			(size 0 0)
			(layers "F.Cu" "F.Mask" "F.Paste")
			(net "PWRGD_P1V2_AUX_R")
		)
	)
)
